# SCM (Grand Teton) — schematic netlist excerpt (pin names and nets, part order shuffled) for the footprints in the layout excerpt that follows; sources: Cadence DE-HDL packaged netlist, KiCad conversion of 12092022_DA0F0TMDCD0_F0T_Management_Board_D_brd_V3_OCP.brd

R125  Q_RES  100 1% CHIP  pkg 0402LF  page 22 : A = RST_BMC_SRST_BUF_R_N ; B = RST_BMC_SRST_N
R664  Q_RES  1K 1% EMPTY  pkg 0402LF  page 21 : A = SPI_BMC_BT_WP1_N_R ; B = GND

(kicad_pcb
	(version 20260206)
	(generator "pcbnew")
	(generator_version "10.0")
	(general
		(thickness 1.6)
		(legacy_teardrops no)
	)
	(paper "A4")
	(title_block
		(title "12092022_DA0F0TMDCD0_F0T_Management_Board_D_brd_V3_OCP.brd")
		(comment 1 "Grand Teton / footprints 360-361 of 1440")
	)
	(layers
		(0 "F.Cu" signal "TOP")
		(4 "In1.Cu" signal "GND")
		(6 "In2.Cu" signal "IN1")
		(8 "In3.Cu" signal "GND1")
		(10 "In4.Cu" signal "IN2")
		(12 "In5.Cu" signal "VCC")
		(14 "In6.Cu" signal "VCC1")
		(16 "In7.Cu" signal "IN3")
		(18 "In8.Cu" signal "GND2")
		(20 "In9.Cu" signal "IN4")
		(22 "In10.Cu" signal "GND3")
		(2 "B.Cu" signal "BOTTOM")
		(9 "F.Adhes" user "F.Adhesive")
		(11 "B.Adhes" user "B.Adhesive")
		(13 "F.Paste" user "Package Geometry/Pastemask Top")
		(15 "B.Paste" user "Package Geometry/Pastemask Bottom")
		(5 "F.SilkS" user "Ref Des/Silkscreen Top")
		(7 "B.SilkS" user "Ref Des/Silkscreen Bottom")
		(1 "F.Mask" user "Board Geometry/Soldermask Top")
		(3 "B.Mask" user "Board Geometry/Soldermask Bottom")
		(17 "Dwgs.User" user "User.Drawings")
		(19 "Cmts.User" user "User.Comments")
		(21 "Eco1.User" user "User.Eco1")
		(23 "Eco2.User" user "User.Eco2")
		(25 "Edge.Cuts" user "Board Geometry/Outline")
		(27 "Margin" user)
		(31 "F.CrtYd" user "Package Geometry/Place Bound Top")
		(29 "B.CrtYd" user "Package Geometry/Place Bound Bottom")
		(35 "F.Fab" user "Ref Des/Assembly Top")
		(33 "B.Fab" user "Ref Des/Assembly Bottom")
	)
	(footprint ""
		(layer "F.Cu")
		(at 10.922 -106.6038)
		(property "Reference" "R125"
			(at 0 0 0)
			(layer "F.SilkS")
			(hide yes)
			(effects
				(font
					(size 1.27 1.27)
				)
			)
		)
		(property "Value" ""
			(at 0 0 0)
			(layer "F.Fab")
			(effects
				(font
					(size 1.27 1.27)
				)
			)
		)
		(duplicate_pad_numbers_are_jumpers no)
		(fp_line
			(start -0.7874 -0.4064)
			(end 0.7874 -0.4064)
			(stroke
				(width 0.1524)
				(type default)
			)
			(layer "F.SilkS")
		)
		(fp_line
			(start -0.7874 0.4064)
			(end -0.7874 -0.4064)
			(stroke
				(width 0.1524)
				(type default)
			)
			(layer "F.SilkS")
		)
		(fp_line
			(start 0.7874 -0.4064)
			(end 0.7874 0.4064)
			(stroke
				(width 0.1524)
				(type default)
			)
			(layer "F.SilkS")
		)
		(fp_line
			(start 0.7874 0.4064)
			(end -0.7874 0.4064)
			(stroke
				(width 0.1524)
				(type default)
			)
			(layer "F.SilkS")
		)
		(fp_line
			(start -0.67945 -0.305054)
			(end -0.12065 -0.305054)
			(stroke
				(width 0.1)
				(type default)
			)
			(layer "F.Fab")
		)
		(fp_line
			(start -0.67945 0.3048)
			(end -0.67945 -0.305054)
			(stroke
				(width 0.1)
				(type default)
			)
			(layer "F.Fab")
		)
		(fp_line
			(start -0.12065 -0.305054)
			(end -0.12065 -0.2794)
			(stroke
				(width 0.1)
				(type default)
			)
			(layer "F.Fab")
		)
		(fp_line
			(start -0.12065 -0.2794)
			(end 0.12065 -0.2794)
			(stroke
				(width 0.1)
				(type default)
			)
			(layer "F.Fab")
		)
		(fp_line
			(start -0.12065 0.2794)
			(end -0.12065 0.3048)
			(stroke
				(width 0.1)
				(type default)
			)
			(layer "F.Fab")
		)
		(fp_line
			(start -0.12065 0.3048)
			(end -0.67945 0.3048)
			(stroke
				(width 0.1)
				(type default)
			)
			(layer "F.Fab")
		)
		(fp_line
			(start 0.120396 0.2794)
			(end -0.12065 0.2794)
			(stroke
				(width 0.1)
				(type default)
			)
			(layer "F.Fab")
		)
		(fp_line
			(start 0.120396 0.3048)
			(end 0.120396 0.2794)
			(stroke
				(width 0.1)
				(type default)
			)
			(layer "F.Fab")
		)
		(fp_line
			(start 0.12065 -0.3048)
			(end 0.67945 -0.3048)
			(stroke
				(width 0.1)
				(type default)
			)
			(layer "F.Fab")
		)
		(fp_line
			(start 0.12065 -0.2794)
			(end 0.12065 -0.3048)
			(stroke
				(width 0.1)
				(type default)
			)
			(layer "F.Fab")
		)
		(fp_line
			(start 0.67945 -0.3048)
			(end 0.67945 0.3048)
			(stroke
				(width 0.1)
				(type default)
			)
			(layer "F.Fab")
		)
		(fp_line
			(start 0.67945 0.3048)
			(end 0.120396 0.3048)
			(stroke
				(width 0.1)
				(type default)
			)
			(layer "F.Fab")
		)
		(pad "1" smd circle
			(at -0.40005 0)
			(size 0 0)
			(layers "F.Cu" "F.Mask" "F.Paste")
			(net "RST_BMC_SRST_BUF_R_N")
		)
		(pad "2" smd circle
			(at 0.40005 0)
			(size 0 0)
			(layers "F.Cu" "F.Mask" "F.Paste")
			(net "RST_BMC_SRST_N")
		)
	)
	(footprint ""
		(layer "F.Cu")
		(at 15.5448 -70.7136 -90)
		(property "Reference" "R664"
			(at 0 0 270)
			(layer "F.SilkS")
			(hide yes)
			(effects
				(font
					(size 1.27 1.27)
				)
			)
		)
		(property "Value" ""
			(at 0 0 270)
			(layer "F.Fab")
			(effects
				(font
					(size 1.27 1.27)
				)
			)
		)
		(duplicate_pad_numbers_are_jumpers no)
		(fp_line
			(start -0.7874 0.4064)
			(end -0.7874 -0.4064)
			(stroke
				(width 0.1524)
				(type default)
			)
			(layer "F.SilkS")
		)
		(fp_line
			(start 0.7874 0.4064)
			(end -0.7874 0.4064)
			(stroke
				(width 0.1524)
				(type default)
			)
			(layer "F.SilkS")
		)
		(fp_line
			(start -0.7874 -0.4064)
			(end 0.7874 -0.4064)
			(stroke
				(width 0.1524)
				(type default)
			)
			(layer "F.SilkS")
		)
		(fp_line
			(start 0.7874 -0.4064)
			(end 0.7874 0.4064)
			(stroke
				(width 0.1524)
				(type default)
			)
			(layer "F.SilkS")
		)
		(fp_line
			(start -0.67945 0.3048)
			(end -0.67945 -0.305054)
			(stroke
				(width 0.1)
				(type default)
			)
			(layer "F.Fab")
		)
		(fp_line
			(start -0.12065 0.3048)
			(end -0.67945 0.3048)
			(stroke
				(width 0.1)
				(type default)
			)
			(layer "F.Fab")
		)
		(fp_line
			(start 0.120396 0.3048)
			(end 0.120396 0.2794)
			(stroke
				(width 0.1)
				(type default)
			)
			(layer "F.Fab")
		)
		(fp_line
			(start 0.67945 0.3048)
			(end 0.120396 0.3048)
			(stroke
				(width 0.1)
				(type default)
			)
			(layer "F.Fab")
		)
		(fp_line
			(start -0.12065 0.2794)
			(end -0.12065 0.3048)
			(stroke
				(width 0.1)
				(type default)
			)
			(layer "F.Fab")
		)
		(fp_line
			(start 0.120396 0.2794)
			(end -0.12065 0.2794)
			(stroke
				(width 0.1)
				(type default)
			)
			(layer "F.Fab")
		)
		(fp_line
			(start -0.12065 -0.2794)
			(end 0.12065 -0.2794)
			(stroke
				(width 0.1)
				(type default)
			)
			(layer "F.Fab")
		)
		(fp_line
			(start 0.12065 -0.2794)
			(end 0.12065 -0.3048)
			(stroke
				(width 0.1)
				(type default)
			)
			(layer "F.Fab")
		)
		(fp_line
			(start 0.12065 -0.3048)
			(end 0.67945 -0.3048)
			(stroke
				(width 0.1)
				(type default)
			)
			(layer "F.Fab")
		)
		(fp_line
			(start 0.67945 -0.3048)
			(end 0.67945 0.3048)
			(stroke
				(width 0.1)
				(type default)
			)
			(layer "F.Fab")
		)
		(fp_line
			(start -0.67945 -0.305054)
			(end -0.12065 -0.305054)
			(stroke
				(width 0.1)
				(type default)
			)
			(layer "F.Fab")
		)
		(fp_line
			(start -0.12065 -0.305054)
			(end -0.12065 -0.2794)
			(stroke
				(width 0.1)
				(type default)
			)
			(layer "F.Fab")
		)
		(pad "1" smd circle
			(at -0.40005 0 270)
			(size 0 0)
			(layers "F.Cu" "F.Mask" "F.Paste")
			(net "SPI_BMC_BT_WP1_N_R")
		)
		(pad "2" smd circle
			(at 0.40005 0 270)
			(size 0 0)
			(layers "F.Cu" "F.Mask" "F.Paste")
			(net "GND")
		)
	)
)
